(kicad_pcb
	(version 20241229)
	(generator "pcbnew")
	(generator_version "9.0")
	(general
		(thickness 1.599998)
		(legacy_teardrops no)
	)
	(paper "A4")
	(title_block
		(date "2023-02-12")
		(rev "1.1.5")
		(comment 9 "footprints 345-350 of 473")
	)
	(layers
		(0 "F.Cu" signal)
		(4 "In1.Cu" power "In1.GND")
		(6 "In2.Cu" signal)
		(8 "In3.Cu" power "In3.GND")
		(10 "In4.Cu" power "In4.VCC")
		(12 "In5.Cu" signal)
		(14 "In6.Cu" power "In6.VCC")
		(2 "B.Cu" signal)
		(9 "F.Adhes" user "F.Adhesive")
		(11 "B.Adhes" user "B.Adhesive")
		(13 "F.Paste" user)
		(15 "B.Paste" user)
		(5 "F.SilkS" user "F.Silkscreen")
		(7 "B.SilkS" user "B.Silkscreen")
		(1 "F.Mask" user)
		(3 "B.Mask" user)
		(17 "Dwgs.User" user "User.Drawings")
		(19 "Cmts.User" user "User.Comments")
		(21 "Eco1.User" user "User.Eco1")
		(23 "Eco2.User" user "User.Eco2")
		(25 "Edge.Cuts" user)
		(27 "Margin" user)
		(31 "F.CrtYd" user "F.Courtyard")
		(29 "B.CrtYd" user "B.Courtyard")
		(35 "F.Fab" user)
		(33 "B.Fab" user)
	)
	(footprint "antmicro-footprints:C_0201"
		(layer "B.Cu")
		(at 172.636328 92.497157 90)
		(descr "Capacitor SMD 0201")
		(tags "capacitor SMD 0201")
		(property "Reference" "C25"
			(at 2.697157 -0.136328 270)
			(layer "B.SilkS")
			(effects
				(font
					(size 0.7 0.7)
					(thickness 0.15)
				)
				(justify left bottom mirror)
			)
		)
		(property "Value" "C_100n_0201"
			(at 0 -1.4 270)
			(layer "B.Fab")
			(effects
				(font
					(size 0.7 0.7)
					(thickness 0.15)
				)
				(justify left bottom mirror)
			)
		)
		(property "Description" " "
			(at 0 0 90)
			(layer "F.Fab")
			(hide yes)
			(effects
				(font
					(size 1.27 1.27)
					(thickness 0.15)
				)
			)
		)
		(property "Author" "Antmicro"
			(at 265.133485 -80.139171 0)
			(layer "B.Fab")
			(hide yes)
			(effects
				(font
					(size 1 1)
					(thickness 0.15)
				)
				(justify mirror)
			)
		)
		(property "Dielectric" ""
			(at 265.133485 -80.139171 0)
			(layer "B.Fab")
			(hide yes)
			(effects
				(font
					(size 1 1)
					(thickness 0.15)
				)
				(justify mirror)
			)
		)
		(property "License" "Apache-2.0"
			(at 265.133485 -80.139171 0)
			(layer "B.Fab")
			(hide yes)
			(effects
				(font
					(size 1 1)
					(thickness 0.15)
				)
				(justify mirror)
			)
		)
		(property "MPN" "CC0201KRX6S5BB104"
			(at 265.133485 -80.139171 0)
			(layer "B.Fab")
			(hide yes)
			(effects
				(font
					(size 1 1)
					(thickness 0.15)
				)
				(justify mirror)
			)
		)
		(property "Manufacturer" "Yaego"
			(at 265.133485 -80.139171 0)
			(layer "B.Fab")
			(hide yes)
			(effects
				(font
					(size 1 1)
					(thickness 0.15)
				)
				(justify mirror)
			)
		)
		(property "Val" "100n"
			(at 265.133485 -80.139171 0)
			(layer "B.Fab")
			(hide yes)
			(effects
				(font
					(size 1 1)
					(thickness 0.15)
				)
				(justify mirror)
			)
		)
		(property "Voltage" ""
			(at 265.133485 -80.139171 0)
			(layer "B.Fab")
			(hide yes)
			(effects
				(font
					(size 1 1)
					(thickness 0.15)
				)
				(justify mirror)
			)
		)
		(sheetname "FPGA power")
		(sheetfile "fpga-power.kicad_sch")
		(attr smd)
		(fp_rect
			(start -0.72 0.38)
			(end 0.72 -0.38)
			(stroke
				(width 0.05)
				(type solid)
			)
			(fill no)
			(layer "B.CrtYd")
		)
		(fp_rect
			(start 0.3 -0.15)
			(end -0.301 0.149)
			(stroke
				(width 0.15)
				(type solid)
			)
			(fill no)
			(layer "B.Fab")
		)
		(pad "" smd roundrect
			(at -0.349 0.002 90)
			(size 0.318 0.36)
			(layers "B.Paste")
			(roundrect_rratio 0.25)
		)
		(pad "" smd roundrect
			(at 0.341 0.002 90)
			(size 0.318 0.36)
			(layers "B.Paste")
			(roundrect_rratio 0.25)
		)
		(pad "1" smd roundrect
			(at -0.321 0.002 90)
			(size 0.46 0.4)
			(layers "B.Cu" "B.Mask")
			(roundrect_rratio 0.25)
			(net 465 "1V0_SYS")
			(pintype "passive")
		)
		(pad "2" smd roundrect
			(at 0.32 0.002 90)
			(size 0.46 0.4)
			(layers "B.Cu" "B.Mask")
			(roundrect_rratio 0.25)
			(net 5 "GND")
			(pintype "passive")
		)
	)
	(footprint "antmicro-footprints:C_0201"
		(layer "B.Cu")
		(at 172.736328 97.497157 90)
		(descr "Capacitor SMD 0201")
		(tags "capacitor SMD 0201")
		(property "Reference" "C33"
			(at 1.097157 1.063672 270)
			(layer "B.SilkS")
			(effects
				(font
					(size 0.7 0.7)
					(thickness 0.15)
				)
				(justify left bottom mirror)
			)
		)
		(property "Value" "C_100n_0201"
			(at 0 -1.4 270)
			(layer "B.Fab")
			(effects
				(font
					(size 0.7 0.7)
					(thickness 0.15)
				)
				(justify left bottom mirror)
			)
		)
		(property "Description" " "
			(at 0 0 90)
			(layer "F.Fab")
			(hide yes)
			(effects
				(font
					(size 1.27 1.27)
					(thickness 0.15)
				)
			)
		)
		(property "Author" "Antmicro"
			(at 270.233485 -75.239171 0)
			(layer "B.Fab")
			(hide yes)
			(effects
				(font
					(size 1 1)
					(thickness 0.15)
				)
				(justify mirror)
			)
		)
		(property "Dielectric" ""
			(at 270.233485 -75.239171 0)
			(layer "B.Fab")
			(hide yes)
			(effects
				(font
					(size 1 1)
					(thickness 0.15)
				)
				(justify mirror)
			)
		)
		(property "License" "Apache-2.0"
			(at 270.233485 -75.239171 0)
			(layer "B.Fab")
			(hide yes)
			(effects
				(font
					(size 1 1)
					(thickness 0.15)
				)
				(justify mirror)
			)
		)
		(property "MPN" "CC0201KRX6S5BB104"
			(at 270.233485 -75.239171 0)
			(layer "B.Fab")
			(hide yes)
			(effects
				(font
					(size 1 1)
					(thickness 0.15)
				)
				(justify mirror)
			)
		)
		(property "Manufacturer" "Yaego"
			(at 270.233485 -75.239171 0)
			(layer "B.Fab")
			(hide yes)
			(effects
				(font
					(size 1 1)
					(thickness 0.15)
				)
				(justify mirror)
			)
		)
		(property "Val" "100n"
			(at 270.233485 -75.239171 0)
			(layer "B.Fab")
			(hide yes)
			(effects
				(font
					(size 1 1)
					(thickness 0.15)
				)
				(justify mirror)
			)
		)
		(property "Voltage" ""
			(at 270.233485 -75.239171 0)
			(layer "B.Fab")
			(hide yes)
			(effects
				(font
					(size 1 1)
					(thickness 0.15)
				)
				(justify mirror)
			)
		)
		(sheetname "FPGA power")
		(sheetfile "fpga-power.kicad_sch")
		(attr smd)
		(fp_rect
			(start -0.72 0.38)
			(end 0.72 -0.38)
			(stroke
				(width 0.05)
				(type solid)
			)
			(fill no)
			(layer "B.CrtYd")
		)
		(fp_rect
			(start 0.3 -0.15)
			(end -0.301 0.149)
			(stroke
				(width 0.15)
				(type solid)
			)
			(fill no)
			(layer "B.Fab")
		)
		(pad "" smd roundrect
			(at -0.349 0.002 90)
			(size 0.318 0.36)
			(layers "B.Paste")
			(roundrect_rratio 0.25)
		)
		(pad "" smd roundrect
			(at 0.341 0.002 90)
			(size 0.318 0.36)
			(layers "B.Paste")
			(roundrect_rratio 0.25)
		)
		(pad "1" smd roundrect
			(at -0.321 0.002 90)
			(size 0.46 0.4)
			(layers "B.Cu" "B.Mask")
			(roundrect_rratio 0.25)
			(net 465 "1V0_SYS")
			(pintype "passive")
		)
		(pad "2" smd roundrect
			(at 0.32 0.002 90)
			(size 0.46 0.4)
			(layers "B.Cu" "B.Mask")
			(roundrect_rratio 0.25)
			(net 5 "GND")
			(pintype "passive")
		)
	)
	(footprint "antmicro-footprints:C_0201"
		(layer "B.Cu")
		(at 173.436328 91.747157 -90)
		(descr "Capacitor SMD 0201")
		(tags "capacitor SMD 0201")
		(property "Reference" "C41"
			(at -3.347157 -1.063672 90)
			(layer "B.SilkS")
			(effects
				(font
					(size 0.7 0.7)
					(thickness 0.15)
				)
				(justify left bottom mirror)
			)
		)
		(property "Value" "C_100n_0201"
			(at 0 -1.4 90)
			(layer "B.Fab")
			(effects
				(font
					(size 0.7 0.7)
					(thickness 0.15)
				)
				(justify left bottom mirror)
			)
		)
		(property "Description" " "
			(at 0 0 270)
			(layer "F.Fab")
			(hide yes)
			(effects
				(font
					(size 1.27 1.27)
					(thickness 0.15)
				)
			)
		)
		(property "Author" "Antmicro"
			(at 81.689171 265.183485 0)
			(layer "B.Fab")
			(hide yes)
			(effects
				(font
					(size 1 1)
					(thickness 0.15)
				)
				(justify mirror)
			)
		)
		(property "Dielectric" ""
			(at 81.689171 265.183485 0)
			(layer "B.Fab")
			(hide yes)
			(effects
				(font
					(size 1 1)
					(thickness 0.15)
				)
				(justify mirror)
			)
		)
		(property "License" "Apache-2.0"
			(at 81.689171 265.183485 0)
			(layer "B.Fab")
			(hide yes)
			(effects
				(font
					(size 1 1)
					(thickness 0.15)
				)
				(justify mirror)
			)
		)
		(property "MPN" "CC0201KRX6S5BB104"
			(at 81.689171 265.183485 0)
			(layer "B.Fab")
			(hide yes)
			(effects
				(font
					(size 1 1)
					(thickness 0.15)
				)
				(justify mirror)
			)
		)
		(property "Manufacturer" "Yaego"
			(at 81.689171 265.183485 0)
			(layer "B.Fab")
			(hide yes)
			(effects
				(font
					(size 1 1)
					(thickness 0.15)
				)
				(justify mirror)
			)
		)
		(property "Val" "100n"
			(at 81.689171 265.183485 0)
			(layer "B.Fab")
			(hide yes)
			(effects
				(font
					(size 1 1)
					(thickness 0.15)
				)
				(justify mirror)
			)
		)
		(property "Voltage" ""
			(at 81.689171 265.183485 0)
			(layer "B.Fab")
			(hide yes)
			(effects
				(font
					(size 1 1)
					(thickness 0.15)
				)
				(justify mirror)
			)
		)
		(sheetname "FPGA power")
		(sheetfile "fpga-power.kicad_sch")
		(attr smd)
		(fp_rect
			(start -0.72 0.38)
			(end 0.72 -0.38)
			(stroke
				(width 0.05)
				(type solid)
			)
			(fill no)
			(layer "B.CrtYd")
		)
		(fp_rect
			(start 0.3 -0.15)
			(end -0.301 0.149)
			(stroke
				(width 0.15)
				(type solid)
			)
			(fill no)
			(layer "B.Fab")
		)
		(pad "" smd roundrect
			(at -0.349 0.002 270)
			(size 0.318 0.36)
			(layers "B.Paste")
			(roundrect_rratio 0.25)
		)
		(pad "" smd roundrect
			(at 0.341 0.002 270)
			(size 0.318 0.36)
			(layers "B.Paste")
			(roundrect_rratio 0.25)
		)
		(pad "1" smd roundrect
			(at -0.321 0.002 270)
			(size 0.46 0.4)
			(layers "B.Cu" "B.Mask")
			(roundrect_rratio 0.25)
			(net 465 "1V0_SYS")
			(pintype "passive")
		)
		(pad "2" smd roundrect
			(at 0.32 0.002 270)
			(size 0.46 0.4)
			(layers "B.Cu" "B.Mask")
			(roundrect_rratio 0.25)
			(net 5 "GND")
			(pintype "passive")
		)
	)
	(footprint "antmicro-footprints:C_0201"
		(layer "B.Cu")
		(at 169.336328 94.017157 -90)
		(descr "Capacitor SMD 0201")
		(tags "capacitor SMD 0201")
		(property "Reference" "C48"
			(at -0.817157 -1.063672 90)
			(layer "B.SilkS")
			(effects
				(font
					(size 0.7 0.7)
					(thickness 0.15)
				)
				(justify left bottom mirror)
			)
		)
		(property "Value" "C_100n_0201"
			(at 0 -1.4 90)
			(layer "B.Fab")
			(effects
				(font
					(size 0.7 0.7)
					(thickness 0.15)
				)
				(justify left bottom mirror)
			)
		)
		(property "Description" " "
			(at 0 0 270)
			(layer "F.Fab")
			(hide yes)
			(effects
				(font
					(size 1.27 1.27)
					(thickness 0.15)
				)
			)
		)
		(property "Author" "Antmicro"
			(at 75.319171 263.353485 0)
			(layer "B.Fab")
			(hide yes)
			(effects
				(font
					(size 1 1)
					(thickness 0.15)
				)
				(justify mirror)
			)
		)
		(property "Dielectric" ""
			(at 75.319171 263.353485 0)
			(layer "B.Fab")
			(hide yes)
			(effects
				(font
					(size 1 1)
					(thickness 0.15)
				)
				(justify mirror)
			)
		)
		(property "License" "Apache-2.0"
			(at 75.319171 263.353485 0)
			(layer "B.Fab")
			(hide yes)
			(effects
				(font
					(size 1 1)
					(thickness 0.15)
				)
				(justify mirror)
			)
		)
		(property "MPN" "CC0201KRX6S5BB104"
			(at 75.319171 263.353485 0)
			(layer "B.Fab")
			(hide yes)
			(effects
				(font
					(size 1 1)
					(thickness 0.15)
				)
				(justify mirror)
			)
		)
		(property "Manufacturer" "Yaego"
			(at 75.319171 263.353485 0)
			(layer "B.Fab")
			(hide yes)
			(effects
				(font
					(size 1 1)
					(thickness 0.15)
				)
				(justify mirror)
			)
		)
		(property "Val" "100n"
			(at 75.319171 263.353485 0)
			(layer "B.Fab")
			(hide yes)
			(effects
				(font
					(size 1 1)
					(thickness 0.15)
				)
				(justify mirror)
			)
		)
		(property "Voltage" ""
			(at 75.319171 263.353485 0)
			(layer "B.Fab")
			(hide yes)
			(effects
				(font
					(size 1 1)
					(thickness 0.15)
				)
				(justify mirror)
			)
		)
		(sheetname "FPGA power")
		(sheetfile "fpga-power.kicad_sch")
		(attr smd)
		(fp_rect
			(start -0.72 0.38)
			(end 0.72 -0.38)
			(stroke
				(width 0.05)
				(type solid)
			)
			(fill no)
			(layer "B.CrtYd")
		)
		(fp_rect
			(start 0.3 -0.15)
			(end -0.301 0.149)
			(stroke
				(width 0.15)
				(type solid)
			)
			(fill no)
			(layer "B.Fab")
		)
		(pad "" smd roundrect
			(at -0.349 0.002 270)
			(size 0.318 0.36)
			(layers "B.Paste")
			(roundrect_rratio 0.25)
		)
		(pad "" smd roundrect
			(at 0.341 0.002 270)
			(size 0.318 0.36)
			(layers "B.Paste")
			(roundrect_rratio 0.25)
		)
		(pad "1" smd roundrect
			(at -0.321 0.002 270)
			(size 0.46 0.4)
			(layers "B.Cu" "B.Mask")
			(roundrect_rratio 0.25)
			(net 465 "1V0_SYS")
			(pintype "passive")
		)
		(pad "2" smd roundrect
			(at 0.32 0.002 270)
			(size 0.46 0.4)
			(layers "B.Cu" "B.Mask")
			(roundrect_rratio 0.25)
			(net 5 "GND")
			(pintype "passive")
		)
	)
	(footprint "antmicro-footprints:C_0201"
		(layer "B.Cu")
		(at 168.661328 99.497157 -90)
		(descr "Capacitor SMD 0201")
		(tags "capacitor SMD 0201")
		(property "Reference" "C59"
			(at 0.502843 -0.538672 90)
			(layer "B.SilkS")
			(effects
				(font
					(size 0.7 0.7)
					(thickness 0.15)
				)
				(justify left bottom mirror)
			)
		)
		(property "Value" "C_100n_0201"
			(at 0 -1.4 90)
			(layer "B.Fab")
			(effects
				(font
					(size 0.7 0.7)
					(thickness 0.15)
				)
				(justify left bottom mirror)
			)
		)
		(property "Description" " "
			(at 0 0 270)
			(layer "F.Fab")
			(hide yes)
			(effects
				(font
					(size 1.27 1.27)
					(thickness 0.15)
				)
			)
		)
		(property "Author" "Antmicro"
			(at 69.164171 268.158485 0)
			(layer "B.Fab")
			(hide yes)
			(effects
				(font
					(size 1 1)
					(thickness 0.15)
				)
				(justify mirror)
			)
		)
		(property "Dielectric" ""
			(at 69.164171 268.158485 0)
			(layer "B.Fab")
			(hide yes)
			(effects
				(font
					(size 1 1)
					(thickness 0.15)
				)
				(justify mirror)
			)
		)
		(property "License" "Apache-2.0"
			(at 69.164171 268.158485 0)
			(layer "B.Fab")
			(hide yes)
			(effects
				(font
					(size 1 1)
					(thickness 0.15)
				)
				(justify mirror)
			)
		)
		(property "MPN" "CC0201KRX6S5BB104"
			(at 69.164171 268.158485 0)
			(layer "B.Fab")
			(hide yes)
			(effects
				(font
					(size 1 1)
					(thickness 0.15)
				)
				(justify mirror)
			)
		)
		(property "Manufacturer" "Yaego"
			(at 69.164171 268.158485 0)
			(layer "B.Fab")
			(hide yes)
			(effects
				(font
					(size 1 1)
					(thickness 0.15)
				)
				(justify mirror)
			)
		)
		(property "Val" "100n"
			(at 69.164171 268.158485 0)
			(layer "B.Fab")
			(hide yes)
			(effects
				(font
					(size 1 1)
					(thickness 0.15)
				)
				(justify mirror)
			)
		)
		(property "Voltage" ""
			(at 69.164171 268.158485 0)
			(layer "B.Fab")
			(hide yes)
			(effects
				(font
					(size 1 1)
					(thickness 0.15)
				)
				(justify mirror)
			)
		)
		(sheetname "FPGA power")
		(sheetfile "fpga-power.kicad_sch")
		(attr smd)
		(fp_rect
			(start -0.72 0.38)
			(end 0.72 -0.38)
			(stroke
				(width 0.05)
				(type solid)
			)
			(fill no)
			(layer "B.CrtYd")
		)
		(fp_rect
			(start 0.3 -0.15)
			(end -0.301 0.149)
			(stroke
				(width 0.15)
				(type solid)
			)
			(fill no)
			(layer "B.Fab")
		)
		(pad "" smd roundrect
			(at -0.349 0.002 270)
			(size 0.318 0.36)
			(layers "B.Paste")
			(roundrect_rratio 0.25)
		)
		(pad "" smd roundrect
			(at 0.341 0.002 270)
			(size 0.318 0.36)
			(layers "B.Paste")
			(roundrect_rratio 0.25)
		)
		(pad "1" smd roundrect
			(at -0.321 0.002 270)
			(size 0.46 0.4)
			(layers "B.Cu" "B.Mask")
			(roundrect_rratio 0.25)
			(net 465 "1V0_SYS")
			(pintype "passive")
		)
		(pad "2" smd roundrect
			(at 0.32 0.002 270)
			(size 0.46 0.4)
			(layers "B.Cu" "B.Mask")
			(roundrect_rratio 0.25)
			(net 5 "GND")
			(pintype "passive")
		)
	)
	(footprint "antmicro-footprints:C_0201"
		(layer "B.Cu")
		(at 165.536328 100.622157)
		(descr "Capacitor SMD 0201")
		(tags "capacitor SMD 0201")
		(property "Reference" "C74"
			(at 0.763672 -0.272157 180)
			(layer "B.SilkS")
			(effects
				(font
					(size 0.7 0.7)
					(thickness 0.15)
				)
				(justify left bottom mirror)
			)
		)
		(property "Value" "C_100n_0201"
			(at 0 -1.4 180)
			(layer "B.Fab")
			(effects
				(font
					(size 0.7 0.7)
					(thickness 0.15)
				)
				(justify left bottom mirror)
			)
		)
		(property "Description" " "
			(at 0 0 0)
			(layer "F.Fab")
			(hide yes)
			(effects
				(font
					(size 1.27 1.27)
					(thickness 0.15)
				)
			)
		)
		(property "Author" "Antmicro"
			(at 0 0 0)
			(layer "B.Fab")
			(hide yes)
			(effects
				(font
					(size 1 1)
					(thickness 0.15)
				)
				(justify mirror)
			)
		)
		(property "Dielectric" ""
			(at 0 0 0)
			(layer "B.Fab")
			(hide yes)
			(effects
				(font
					(size 1 1)
					(thickness 0.15)
				)
				(justify mirror)
			)
		)
		(property "License" "Apache-2.0"
			(at 0 0 0)
			(layer "B.Fab")
			(hide yes)
			(effects
				(font
					(size 1 1)
					(thickness 0.15)
				)
				(justify mirror)
			)
		)
		(property "MPN" "CC0201KRX6S5BB104"
			(at 0 0 0)
			(layer "B.Fab")
			(hide yes)
			(effects
				(font
					(size 1 1)
					(thickness 0.15)
				)
				(justify mirror)
			)
		)
		(property "Manufacturer" "Yaego"
			(at 0 0 0)
			(layer "B.Fab")
			(hide yes)
			(effects
				(font
					(size 1 1)
					(thickness 0.15)
				)
				(justify mirror)
			)
		)
		(property "Val" "100n"
			(at 0 0 0)
			(layer "B.Fab")
			(hide yes)
			(effects
				(font
					(size 1 1)
					(thickness 0.15)
				)
				(justify mirror)
			)
		)
		(property "Voltage" ""
			(at 0 0 0)
			(layer "B.Fab")
			(hide yes)
			(effects
				(font
					(size 1 1)
					(thickness 0.15)
				)
				(justify mirror)
			)
		)
		(sheetname "FPGA power")
		(sheetfile "fpga-power.kicad_sch")
		(attr smd)
		(fp_rect
			(start -0.72 0.38)
			(end 0.72 -0.38)
			(stroke
				(width 0.05)
				(type solid)
			)
			(fill no)
			(layer "B.CrtYd")
		)
		(fp_rect
			(start 0.3 -0.15)
			(end -0.301 0.149)
			(stroke
				(width 0.15)
				(type solid)
			)
			(fill no)
			(layer "B.Fab")
		)
		(pad "" smd roundrect
			(at -0.349 0.002)
			(size 0.318 0.36)
			(layers "B.Paste")
			(roundrect_rratio 0.25)
		)
		(pad "" smd roundrect
			(at 0.341 0.002)
			(size 0.318 0.36)
			(layers "B.Paste")
			(roundrect_rratio 0.25)
		)
		(pad "1" smd roundrect
			(at -0.321 0.002)
			(size 0.46 0.4)
			(layers "B.Cu" "B.Mask")
			(roundrect_rratio 0.25)
			(net 465 "1V0_SYS")
			(pintype "passive")
		)
		(pad "2" smd roundrect
			(at 0.32 0.002)
			(size 0.46 0.4)
			(layers "B.Cu" "B.Mask")
			(roundrect_rratio 0.25)
			(net 5 "GND")
			(pintype "passive")
		)
	)
)
